FILE_TYPE=LIBRARY_PARTS;
primitive 'LCMXO3LF2100C5BG256C';
  pin
    'VCCIO0_D5':
      PIN_NUMBER='(D5,0,0,0,0,0,0)';
      PINUSE='POWER';
      NO_LOAD_CHECK='Both';
      NO_IO_CHECK='Both';
      NO_ASSERT_CHECK='TRUE';
      NO_DIR_CHECK='TRUE';
      ALLOW_CONNECT='TRUE';
    'VCCIO0_D12':
      PIN_NUMBER='(D12,0,0,0,0,0,0)';
      PINUSE='POWER';
      NO_LOAD_CHECK='Both';
      NO_IO_CHECK='Both';
      NO_ASSERT_CHECK='TRUE';
      NO_DIR_CHECK='TRUE';
      ALLOW_CONNECT='TRUE';
    'VCCIO0_G8':
      PIN_NUMBER='(G8,0,0,0,0,0,0)';
      PINUSE='POWER';
      NO_LOAD_CHECK='Both';
      NO_IO_CHECK='Both';
      NO_ASSERT_CHECK='TRUE';
      NO_DIR_CHECK='TRUE';
      ALLOW_CONNECT='TRUE';
    'VCCIO0_G9':
      PIN_NUMBER='(G9,0,0,0,0,0,0)';
      PINUSE='POWER';
      NO_LOAD_CHECK='Both';
      NO_IO_CHECK='Both';
      NO_ASSERT_CHECK='TRUE';
      NO_DIR_CHECK='TRUE';
      ALLOW_CONNECT='TRUE';
    'PT9A':
      PIN_NUMBER='(C4,0,0,0,0,0,0)';
      BIDIRECTIONAL='TRUE';
      INPUT_LOAD='(-0.01,0.01)';
      OUTPUT_LOAD='(1.0,-1.0)';
    'PT9B':
      PIN_NUMBER='(B5,0,0,0,0,0,0)';
      BIDIRECTIONAL='TRUE';
      INPUT_LOAD='(-0.01,0.01)';
      OUTPUT_LOAD='(1.0,-1.0)';
    'PT9C':
      PIN_NUMBER='(B3,0,0,0,0,0,0)';
      BIDIRECTIONAL='TRUE';
      INPUT_LOAD='(-0.01,0.01)';
      OUTPUT_LOAD='(1.0,-1.0)';
    'PT10A':
      PIN_NUMBER='(A4,0,0,0,0,0,0)';
      BIDIRECTIONAL='TRUE';
      INPUT_LOAD='(-0.01,0.01)';
      OUTPUT_LOAD='(1.0,-1.0)';
    'PT10B':
      PIN_NUMBER='(C5,0,0,0,0,0,0)';
      BIDIRECTIONAL='TRUE';
      INPUT_LOAD='(-0.01,0.01)';
      OUTPUT_LOAD='(1.0,-1.0)';
    'PT11A':
      PIN_NUMBER='(A5,0,0,0,0,0,0)';
      BIDIRECTIONAL='TRUE';
      INPUT_LOAD='(-0.01,0.01)';
      OUTPUT_LOAD='(1.0,-1.0)';
    'PT11B':
      PIN_NUMBER='(B6,0,0,0,0,0,0)';
      BIDIRECTIONAL='TRUE';
      INPUT_LOAD='(-0.01,0.01)';
      OUTPUT_LOAD='(1.0,-1.0)';
    'PT11C':
      PIN_NUMBER='(A3,0,0,0,0,0,0)';
      BIDIRECTIONAL='TRUE';
      INPUT_LOAD='(-0.01,0.01)';
      OUTPUT_LOAD='(1.0,-1.0)';
    'PT11D':
      PIN_NUMBER='(B4,0,0,0,0,0,0)';
      BIDIRECTIONAL='TRUE';
      INPUT_LOAD='(-0.01,0.01)';
      OUTPUT_LOAD='(1.0,-1.0)';
    'PT12A':
      PIN_NUMBER='(D6,0,0,0,0,0,0)';
      BIDIRECTIONAL='TRUE';
      INPUT_LOAD='(-0.01,0.01)';
      OUTPUT_LOAD='(1.0,-1.0)';
    'PT12B':
      PIN_NUMBER='(E7,0,0,0,0,0,0)';
      BIDIRECTIONAL='TRUE';
      INPUT_LOAD='(-0.01,0.01)';
      OUTPUT_LOAD='(1.0,-1.0)';
    'PT12C||TDO':
      PIN_NUMBER='(C6,0,0,0,0,0,0)';
      BIDIRECTIONAL='TRUE';
      INPUT_LOAD='(-0.01,0.01)';
      OUTPUT_LOAD='(1.0,-1.0)';
    'PT12D||TDI':
      PIN_NUMBER='(A6,0,0,0,0,0,0)';
      BIDIRECTIONAL='TRUE';
      INPUT_LOAD='(-0.01,0.01)';
      OUTPUT_LOAD='(1.0,-1.0)';
    'PT13A':
      PIN_NUMBER='(B7,0,0,0,0,0,0)';
      BIDIRECTIONAL='TRUE';
      INPUT_LOAD='(-0.01,0.01)';
      OUTPUT_LOAD='(1.0,-1.0)';
    'PT13B':
      PIN_NUMBER='(C7,0,0,0,0,0,0)';
      BIDIRECTIONAL='TRUE';
      INPUT_LOAD='(-0.01,0.01)';
      OUTPUT_LOAD='(1.0,-1.0)';
    'PT13C':
      PIN_NUMBER='(E6,0,0,0,0,0,0)';
      BIDIRECTIONAL='TRUE';
      INPUT_LOAD='(-0.01,0.01)';
      OUTPUT_LOAD='(1.0,-1.0)';
    'PT13D':
      PIN_NUMBER='(D7,0,0,0,0,0,0)';
      BIDIRECTIONAL='TRUE';
      INPUT_LOAD='(-0.01,0.01)';
      OUTPUT_LOAD='(1.0,-1.0)';
    'PT16A':
      PIN_NUMBER='(F7,0,0,0,0,0,0)';
      BIDIRECTIONAL='TRUE';
      INPUT_LOAD='(-0.01,0.01)';
      OUTPUT_LOAD='(1.0,-1.0)';
    'PT16B':
      PIN_NUMBER='(E8,0,0,0,0,0,0)';
      BIDIRECTIONAL='TRUE';
      INPUT_LOAD='(-0.01,0.01)';
      OUTPUT_LOAD='(1.0,-1.0)';
    'PT16C||TCK':
      PIN_NUMBER='(A7,0,0,0,0,0,0)';
      BIDIRECTIONAL='TRUE';
      INPUT_LOAD='(-0.01,0.01)';
      OUTPUT_LOAD='(1.0,-1.0)';
    'PT16D||TMS':
      PIN_NUMBER='(B8,0,0,0,0,0,0)';
      BIDIRECTIONAL='TRUE';
      INPUT_LOAD='(-0.01,0.01)';
      OUTPUT_LOAD='(1.0,-1.0)';
    'PT17A||PCLKT0_1':
      PIN_NUMBER='(C8,0,0,0,0,0,0)';
      BIDIRECTIONAL='TRUE';
      INPUT_LOAD='(-0.01,0.01)';
      OUTPUT_LOAD='(1.0,-1.0)';
    'PT17B||PCLKC0_1':
      PIN_NUMBER='(A8,0,0,0,0,0,0)';
      BIDIRECTIONAL='TRUE';
      INPUT_LOAD='(-0.01,0.01)';
      OUTPUT_LOAD='(1.0,-1.0)';
    'PT17C':
      PIN_NUMBER='(D8,0,0,0,0,0,0)';
      BIDIRECTIONAL='TRUE';
      INPUT_LOAD='(-0.01,0.01)';
      OUTPUT_LOAD='(1.0,-1.0)';
    'PT17D':
      PIN_NUMBER='(E9,0,0,0,0,0,0)';
      BIDIRECTIONAL='TRUE';
      INPUT_LOAD='(-0.01,0.01)';
      OUTPUT_LOAD='(1.0,-1.0)';
    'PT18B':
      PIN_NUMBER='(D9,0,0,0,0,0,0)';
      BIDIRECTIONAL='TRUE';
      INPUT_LOAD='(-0.01,0.01)';
      OUTPUT_LOAD='(1.0,-1.0)';
    'PT18C||SCL||PCLKT0_0':
      PIN_NUMBER='(A9,0,0,0,0,0,0)';
      BIDIRECTIONAL='TRUE';
      INPUT_LOAD='(-0.01,0.01)';
      OUTPUT_LOAD='(1.0,-1.0)';
    'PT18D||SDA||PCLKC0_0':
      PIN_NUMBER='(C9,0,0,0,0,0,0)';
      BIDIRECTIONAL='TRUE';
      INPUT_LOAD='(-0.01,0.01)';
      OUTPUT_LOAD='(1.0,-1.0)';
    'PT19A':
      PIN_NUMBER='(B9,0,0,0,0,0,0)';
      BIDIRECTIONAL='TRUE';
      INPUT_LOAD='(-0.01,0.01)';
      OUTPUT_LOAD='(1.0,-1.0)';
    'PT19B':
      PIN_NUMBER='(A10,0,0,0,0,0,0)';
      BIDIRECTIONAL='TRUE';
      INPUT_LOAD='(-0.01,0.01)';
      OUTPUT_LOAD='(1.0,-1.0)';
    'PT19C':
      PIN_NUMBER='(F9,0,0,0,0,0,0)';
      BIDIRECTIONAL='TRUE';
      INPUT_LOAD='(-0.01,0.01)';
      OUTPUT_LOAD='(1.0,-1.0)';
    'PT19D':
      PIN_NUMBER='(E11,0,0,0,0,0,0)';
      BIDIRECTIONAL='TRUE';
      INPUT_LOAD='(-0.01,0.01)';
      OUTPUT_LOAD='(1.0,-1.0)';
    'PT20A':
      PIN_NUMBER='(D10,0,0,0,0,0,0)';
      BIDIRECTIONAL='TRUE';
      INPUT_LOAD='(-0.01,0.01)';
      OUTPUT_LOAD='(1.0,-1.0)';
    'PT20B':
      PIN_NUMBER='(E10,0,0,0,0,0,0)';
      BIDIRECTIONAL='TRUE';
      INPUT_LOAD='(-0.01,0.01)';
      OUTPUT_LOAD='(1.0,-1.0)';
    'PT20C||JTAGENB':
      PIN_NUMBER='(C10,0,0,0,0,0,0)';
      BIDIRECTIONAL='TRUE';
      INPUT_LOAD='(-0.01,0.01)';
      OUTPUT_LOAD='(1.0,-1.0)';
    'PT20D||PROGRAMN':
      PIN_NUMBER='(B10,0,0,0,0,0,0)';
      BIDIRECTIONAL='TRUE';
      INPUT_LOAD='(-0.01,0.01)';
      OUTPUT_LOAD='(1.0,-1.0)';
    'PT21A':
      PIN_NUMBER='(A11,0,0,0,0,0,0)';
      BIDIRECTIONAL='TRUE';
      INPUT_LOAD='(-0.01,0.01)';
      OUTPUT_LOAD='(1.0,-1.0)';
    'PT21B':
      PIN_NUMBER='(C11,0,0,0,0,0,0)';
      BIDIRECTIONAL='TRUE';
      INPUT_LOAD='(-0.01,0.01)';
      OUTPUT_LOAD='(1.0,-1.0)';
    'PT21C':
      PIN_NUMBER='(F10,0,0,0,0,0,0)';
      BIDIRECTIONAL='TRUE';
      INPUT_LOAD='(-0.01,0.01)';
      OUTPUT_LOAD='(1.0,-1.0)';
    'PT21D':
      PIN_NUMBER='(D11,0,0,0,0,0,0)';
      BIDIRECTIONAL='TRUE';
      INPUT_LOAD='(-0.01,0.01)';
      OUTPUT_LOAD='(1.0,-1.0)';
    'PT22A':
      PIN_NUMBER='(B11,0,0,0,0,0,0)';
      BIDIRECTIONAL='TRUE';
      INPUT_LOAD='(-0.01,0.01)';
      OUTPUT_LOAD='(1.0,-1.0)';
    'PT22B':
      PIN_NUMBER='(A12,0,0,0,0,0,0)';
      BIDIRECTIONAL='TRUE';
      INPUT_LOAD='(-0.01,0.01)';
      OUTPUT_LOAD='(1.0,-1.0)';
    'PT22C':
      PIN_NUMBER='(B13,0,0,0,0,0,0)';
      BIDIRECTIONAL='TRUE';
      INPUT_LOAD='(-0.01,0.01)';
      OUTPUT_LOAD='(1.0,-1.0)';
    'PT22D':
      PIN_NUMBER='(A14,0,0,0,0,0,0)';
      BIDIRECTIONAL='TRUE';
      INPUT_LOAD='(-0.01,0.01)';
      OUTPUT_LOAD='(1.0,-1.0)';
    'PT23A':
      PIN_NUMBER='(C12,0,0,0,0,0,0)';
      BIDIRECTIONAL='TRUE';
      INPUT_LOAD='(-0.01,0.01)';
      OUTPUT_LOAD='(1.0,-1.0)';
    'PT23B':
      PIN_NUMBER='(B12,0,0,0,0,0,0)';
      BIDIRECTIONAL='TRUE';
      INPUT_LOAD='(-0.01,0.01)';
      OUTPUT_LOAD='(1.0,-1.0)';
    'PT24A':
      PIN_NUMBER='(B14,0,0,0,0,0,0)';
      BIDIRECTIONAL='TRUE';
      INPUT_LOAD='(-0.01,0.01)';
      OUTPUT_LOAD='(1.0,-1.0)';
    'PT24B':
      PIN_NUMBER='(A15,0,0,0,0,0,0)';
      BIDIRECTIONAL='TRUE';
      INPUT_LOAD='(-0.01,0.01)';
      OUTPUT_LOAD='(1.0,-1.0)';
    'PT24C||INITN':
      PIN_NUMBER='(A13,0,0,0,0,0,0)';
      BIDIRECTIONAL='TRUE';
      INPUT_LOAD='(-0.01,0.01)';
      OUTPUT_LOAD='(1.0,-1.0)';
    'PT24D||DONE':
      PIN_NUMBER='(C13,0,0,0,0,0,0)';
      BIDIRECTIONAL='TRUE';
      INPUT_LOAD='(-0.01,0.01)';
      OUTPUT_LOAD='(1.0,-1.0)';
    'PT18A':
      PIN_NUMBER='(F8,0,0,0,0,0,0)';
      BIDIRECTIONAL='TRUE';
      INPUT_LOAD='(-0.01,0.01)';
      OUTPUT_LOAD='(1.0,-1.0)';
    'PR10C':
      PIN_NUMBER='(0,J11,0,0,0,0,0)';
      BIDIRECTIONAL='TRUE';
      INPUT_LOAD='(-0.01,0.01)';
      OUTPUT_LOAD='(1.0,-1.0)';
    'PR10D':
      PIN_NUMBER='(0,L12,0,0,0,0,0)';
      BIDIRECTIONAL='TRUE';
      INPUT_LOAD='(-0.01,0.01)';
      OUTPUT_LOAD='(1.0,-1.0)';
    'PR6A':
      PIN_NUMBER='(0,G16,0,0,0,0,0)';
      BIDIRECTIONAL='TRUE';
      INPUT_LOAD='(-0.01,0.01)';
      OUTPUT_LOAD='(1.0,-1.0)';
    'PR6B':
      PIN_NUMBER='(0,H15,0,0,0,0,0)';
      BIDIRECTIONAL='TRUE';
      INPUT_LOAD='(-0.01,0.01)';
      OUTPUT_LOAD='(1.0,-1.0)';
    'PR12C':
      PIN_NUMBER='(0,K11,0,0,0,0,0)';
      BIDIRECTIONAL='TRUE';
      INPUT_LOAD='(-0.01,0.01)';
      OUTPUT_LOAD='(1.0,-1.0)';
    'PR12D':
      PIN_NUMBER='(0,L13,0,0,0,0,0)';
      BIDIRECTIONAL='TRUE';
      INPUT_LOAD='(-0.01,0.01)';
      OUTPUT_LOAD='(1.0,-1.0)';
    'PR7A||PCLKT1_0':
      PIN_NUMBER='(0,H14,0,0,0,0,0)';
      BIDIRECTIONAL='TRUE';
      INPUT_LOAD='(-0.01,0.01)';
      OUTPUT_LOAD='(1.0,-1.0)';
    'PR7B||PCLKC1_0':
      PIN_NUMBER='(0,H16,0,0,0,0,0)';
      BIDIRECTIONAL='TRUE';
      INPUT_LOAD='(-0.01,0.01)';
      OUTPUT_LOAD='(1.0,-1.0)';
    'PR13C':
      PIN_NUMBER='(0,N15,0,0,0,0,0)';
      BIDIRECTIONAL='TRUE';
      INPUT_LOAD='(-0.01,0.01)';
      OUTPUT_LOAD='(1.0,-1.0)';
    'PR13D':
      PIN_NUMBER='(0,P16,0,0,0,0,0)';
      BIDIRECTIONAL='TRUE';
      INPUT_LOAD='(-0.01,0.01)';
      OUTPUT_LOAD='(1.0,-1.0)';
    'PR14A':
      PIN_NUMBER='(0,N16,0,0,0,0,0)';
      BIDIRECTIONAL='TRUE';
      INPUT_LOAD='(-0.01,0.01)';
      OUTPUT_LOAD='(1.0,-1.0)';
    'PR14B':
      PIN_NUMBER='(0,N14,0,0,0,0,0)';
      BIDIRECTIONAL='TRUE';
      INPUT_LOAD='(-0.01,0.01)';
      OUTPUT_LOAD='(1.0,-1.0)';
    'PR14C':
      PIN_NUMBER='(0,P15,0,0,0,0,0)';
      BIDIRECTIONAL='TRUE';
      INPUT_LOAD='(-0.01,0.01)';
      OUTPUT_LOAD='(1.0,-1.0)';
    'PR14D':
      PIN_NUMBER='(0,R16,0,0,0,0,0)';
      BIDIRECTIONAL='TRUE';
      INPUT_LOAD='(-0.01,0.01)';
      OUTPUT_LOAD='(1.0,-1.0)';
    'PR13A':
      PIN_NUMBER='(0,M14,0,0,0,0,0)';
      BIDIRECTIONAL='TRUE';
      INPUT_LOAD='(-0.01,0.01)';
      OUTPUT_LOAD='(1.0,-1.0)';
    'PR13B':
      PIN_NUMBER='(0,M15,0,0,0,0,0)';
      BIDIRECTIONAL='TRUE';
      INPUT_LOAD='(-0.01,0.01)';
      OUTPUT_LOAD='(1.0,-1.0)';
    'PR12A':
      PIN_NUMBER='(0,L15,0,0,0,0,0)';
      BIDIRECTIONAL='TRUE';
      INPUT_LOAD='(-0.01,0.01)';
      OUTPUT_LOAD='(1.0,-1.0)';
    'PR12B':
      PIN_NUMBER='(0,M16,0,0,0,0,0)';
      BIDIRECTIONAL='TRUE';
      INPUT_LOAD='(-0.01,0.01)';
      OUTPUT_LOAD='(1.0,-1.0)';
    'PR11C':
      PIN_NUMBER='(0,K13,0,0,0,0,0)';
      BIDIRECTIONAL='TRUE';
      INPUT_LOAD='(-0.01,0.01)';
      OUTPUT_LOAD='(1.0,-1.0)';
    'PR11D':
      PIN_NUMBER='(0,K12,0,0,0,0,0)';
      BIDIRECTIONAL='TRUE';
      INPUT_LOAD='(-0.01,0.01)';
      OUTPUT_LOAD='(1.0,-1.0)';
    'PR11A':
      PIN_NUMBER='(0,L16,0,0,0,0,0)';
      BIDIRECTIONAL='TRUE';
      INPUT_LOAD='(-0.01,0.01)';
      OUTPUT_LOAD='(1.0,-1.0)';
    'PR11B':
      PIN_NUMBER='(0,L14,0,0,0,0,0)';
      BIDIRECTIONAL='TRUE';
      INPUT_LOAD='(-0.01,0.01)';
      OUTPUT_LOAD='(1.0,-1.0)';
    'PR10A':
      PIN_NUMBER='(0,K14,0,0,0,0,0)';
      BIDIRECTIONAL='TRUE';
      INPUT_LOAD='(-0.01,0.01)';
      OUTPUT_LOAD='(1.0,-1.0)';
    'PR10B':
      PIN_NUMBER='(0,K15,0,0,0,0,0)';
      BIDIRECTIONAL='TRUE';
      INPUT_LOAD='(-0.01,0.01)';
      OUTPUT_LOAD='(1.0,-1.0)';
    'PR9A':
      PIN_NUMBER='(0,J15,0,0,0,0,0)';
      BIDIRECTIONAL='TRUE';
      INPUT_LOAD='(-0.01,0.01)';
      OUTPUT_LOAD='(1.0,-1.0)';
    'PR9B':
      PIN_NUMBER='(0,K16,0,0,0,0,0)';
      BIDIRECTIONAL='TRUE';
      INPUT_LOAD='(-0.01,0.01)';
      OUTPUT_LOAD='(1.0,-1.0)';
    'PR1A':
      PIN_NUMBER='(0,D14,0,0,0,0,0)';
      BIDIRECTIONAL='TRUE';
      INPUT_LOAD='(-0.01,0.01)';
      OUTPUT_LOAD='(1.0,-1.0)';
    'PR1B':
      PIN_NUMBER='(0,E15,0,0,0,0,0)';
      BIDIRECTIONAL='TRUE';
      INPUT_LOAD='(-0.01,0.01)';
      OUTPUT_LOAD='(1.0,-1.0)';
    'PR1C':
      PIN_NUMBER='(0,C15,0,0,0,0,0)';
      BIDIRECTIONAL='TRUE';
      INPUT_LOAD='(-0.01,0.01)';
      OUTPUT_LOAD='(1.0,-1.0)';
    'PR1D':
      PIN_NUMBER='(0,B16,0,0,0,0,0)';
      BIDIRECTIONAL='TRUE';
      INPUT_LOAD='(-0.01,0.01)';
      OUTPUT_LOAD='(1.0,-1.0)';
    'PR2A':
      PIN_NUMBER='(0,D16,0,0,0,0,0)';
      BIDIRECTIONAL='TRUE';
      INPUT_LOAD='(-0.01,0.01)';
      OUTPUT_LOAD='(1.0,-1.0)';
    'PR2B':
      PIN_NUMBER='(0,E14,0,0,0,0,0)';
      BIDIRECTIONAL='TRUE';
      INPUT_LOAD='(-0.01,0.01)';
      OUTPUT_LOAD='(1.0,-1.0)';
    'PR2C':
      PIN_NUMBER='(0,C16,0,0,0,0,0)';
      BIDIRECTIONAL='TRUE';
      INPUT_LOAD='(-0.01,0.01)';
      OUTPUT_LOAD='(1.0,-1.0)';
    'PR2D':
      PIN_NUMBER='(0,D15,0,0,0,0,0)';
      BIDIRECTIONAL='TRUE';
      INPUT_LOAD='(-0.01,0.01)';
      OUTPUT_LOAD='(1.0,-1.0)';
    'PR3C':
      PIN_NUMBER='(0,F13,0,0,0,0,0)';
      BIDIRECTIONAL='TRUE';
      INPUT_LOAD='(-0.01,0.01)';
      OUTPUT_LOAD='(1.0,-1.0)';
    'PR3D':
      PIN_NUMBER='(0,G12,0,0,0,0,0)';
      BIDIRECTIONAL='TRUE';
      INPUT_LOAD='(-0.01,0.01)';
      OUTPUT_LOAD='(1.0,-1.0)';
    'PR4C':
      PIN_NUMBER='(0,F12,0,0,0,0,0)';
      BIDIRECTIONAL='TRUE';
      INPUT_LOAD='(-0.01,0.01)';
      OUTPUT_LOAD='(1.0,-1.0)';
    'PR4D':
      PIN_NUMBER='(0,G13,0,0,0,0,0)';
      BIDIRECTIONAL='TRUE';
      INPUT_LOAD='(-0.01,0.01)';
      OUTPUT_LOAD='(1.0,-1.0)';
    'PR3A':
      PIN_NUMBER='(0,E16,0,0,0,0,0)';
      BIDIRECTIONAL='TRUE';
      INPUT_LOAD='(-0.01,0.01)';
      OUTPUT_LOAD='(1.0,-1.0)';
    'PR3B':
      PIN_NUMBER='(0,F15,0,0,0,0,0)';
      BIDIRECTIONAL='TRUE';
      INPUT_LOAD='(-0.01,0.01)';
      OUTPUT_LOAD='(1.0,-1.0)';
    'PR5C':
      PIN_NUMBER='(0,G11,0,0,0,0,0)';
      BIDIRECTIONAL='TRUE';
      INPUT_LOAD='(-0.01,0.01)';
      OUTPUT_LOAD='(1.0,-1.0)';
    'PR5D':
      PIN_NUMBER='(0,H12,0,0,0,0,0)';
      BIDIRECTIONAL='TRUE';
      INPUT_LOAD='(-0.01,0.01)';
      OUTPUT_LOAD='(1.0,-1.0)';
    'PR4A':
      PIN_NUMBER='(0,F14,0,0,0,0,0)';
      BIDIRECTIONAL='TRUE';
      INPUT_LOAD='(-0.01,0.01)';
      OUTPUT_LOAD='(1.0,-1.0)';
    'PR4B':
      PIN_NUMBER='(0,F16,0,0,0,0,0)';
      BIDIRECTIONAL='TRUE';
      INPUT_LOAD='(-0.01,0.01)';
      OUTPUT_LOAD='(1.0,-1.0)';
    'PR6C':
      PIN_NUMBER='(0,H13,0,0,0,0,0)';
      BIDIRECTIONAL='TRUE';
      INPUT_LOAD='(-0.01,0.01)';
      OUTPUT_LOAD='(1.0,-1.0)';
    'PR6D':
      PIN_NUMBER='(0,J12,0,0,0,0,0)';
      BIDIRECTIONAL='TRUE';
      INPUT_LOAD='(-0.01,0.01)';
      OUTPUT_LOAD='(1.0,-1.0)';
    'PR7C':
      PIN_NUMBER='(0,J16,0,0,0,0,0)';
      BIDIRECTIONAL='TRUE';
      INPUT_LOAD='(-0.01,0.01)';
      OUTPUT_LOAD='(1.0,-1.0)';
    'PR7D':
      PIN_NUMBER='(0,J14,0,0,0,0,0)';
      BIDIRECTIONAL='TRUE';
      INPUT_LOAD='(-0.01,0.01)';
      OUTPUT_LOAD='(1.0,-1.0)';
    'PR9C':
      PIN_NUMBER='(0,H11,0,0,0,0,0)';
      BIDIRECTIONAL='TRUE';
      INPUT_LOAD='(-0.01,0.01)';
      OUTPUT_LOAD='(1.0,-1.0)';
    'PR9D':
      PIN_NUMBER='(0,J13,0,0,0,0,0)';
      BIDIRECTIONAL='TRUE';
      INPUT_LOAD='(-0.01,0.01)';
      OUTPUT_LOAD='(1.0,-1.0)';
    'PR5A':
      PIN_NUMBER='(0,G15,0,0,0,0,0)';
      BIDIRECTIONAL='TRUE';
      INPUT_LOAD='(-0.01,0.01)';
      OUTPUT_LOAD='(1.0,-1.0)';
    'PR5B':
      PIN_NUMBER='(0,G14,0,0,0,0,0)';
      BIDIRECTIONAL='TRUE';
      INPUT_LOAD='(-0.01,0.01)';
      OUTPUT_LOAD='(1.0,-1.0)';
    'VCCIO1_M13':
      PIN_NUMBER='(0,M13,0,0,0,0,0)';
      PINUSE='POWER';
      NO_LOAD_CHECK='Both';
      NO_IO_CHECK='Both';
      NO_ASSERT_CHECK='TRUE';
      NO_DIR_CHECK='TRUE';
      ALLOW_CONNECT='TRUE';
    'VCCIO1_J10':
      PIN_NUMBER='(0,J10,0,0,0,0,0)';
      PINUSE='POWER';
      NO_LOAD_CHECK='Both';
      NO_IO_CHECK='Both';
      NO_ASSERT_CHECK='TRUE';
      NO_DIR_CHECK='TRUE';
      ALLOW_CONNECT='TRUE';
    'VCCIO1_E13':
      PIN_NUMBER='(0,E13,0,0,0,0,0)';
      PINUSE='POWER';
      NO_LOAD_CHECK='Both';
      NO_IO_CHECK='Both';
      NO_ASSERT_CHECK='TRUE';
      NO_DIR_CHECK='TRUE';
      ALLOW_CONNECT='TRUE';
    'VCCIO1_H10':
      PIN_NUMBER='(0,H10,0,0,0,0,0)';
      PINUSE='POWER';
      NO_LOAD_CHECK='Both';
      NO_IO_CHECK='Both';
      NO_ASSERT_CHECK='TRUE';
      NO_DIR_CHECK='TRUE';
      ALLOW_CONNECT='TRUE';
    'PB9C':
      PIN_NUMBER='(0,0,M7,0,0,0,0)';
      BIDIRECTIONAL='TRUE';
      INPUT_LOAD='(-0.01,0.01)';
      OUTPUT_LOAD='(1.0,-1.0)';
    'PB9D':
      PIN_NUMBER='(0,0,N7,0,0,0,0)';
      BIDIRECTIONAL='TRUE';
      INPUT_LOAD='(-0.01,0.01)';
      OUTPUT_LOAD='(1.0,-1.0)';
    'PB11C':
      PIN_NUMBER='(0,0,M6,0,0,0,0)';
      BIDIRECTIONAL='TRUE';
      INPUT_LOAD='(-0.01,0.01)';
      OUTPUT_LOAD='(1.0,-1.0)';
    'PB11D':
      PIN_NUMBER='(0,0,L8,0,0,0,0)';
      BIDIRECTIONAL='TRUE';
      INPUT_LOAD='(-0.01,0.01)';
      OUTPUT_LOAD='(1.0,-1.0)';
    'PB11A||PCLKT2_0':
      PIN_NUMBER='(0,0,T7,0,0,0,0)';
      BIDIRECTIONAL='TRUE';
      INPUT_LOAD='(-0.01,0.01)';
      OUTPUT_LOAD='(1.0,-1.0)';
    'PB11B||PCLKC2_0':
      PIN_NUMBER='(0,0,R8,0,0,0,0)';
      BIDIRECTIONAL='TRUE';
      INPUT_LOAD='(-0.01,0.01)';
      OUTPUT_LOAD='(1.0,-1.0)';
    'PB12A':
      PIN_NUMBER='(0,0,P8,0,0,0,0)';
      BIDIRECTIONAL='TRUE';
      INPUT_LOAD='(-0.01,0.01)';
      OUTPUT_LOAD='(1.0,-1.0)';
    'PB12B':
      PIN_NUMBER='(0,0,T8,0,0,0,0)';
      BIDIRECTIONAL='TRUE';
      INPUT_LOAD='(-0.01,0.01)';
      OUTPUT_LOAD='(1.0,-1.0)';
    'PB12C':
      PIN_NUMBER='(0,0,N8,0,0,0,0)';
      BIDIRECTIONAL='TRUE';
      INPUT_LOAD='(-0.01,0.01)';
      OUTPUT_LOAD='(1.0,-1.0)';
    'PB12D':
      PIN_NUMBER='(0,0,L9,0,0,0,0)';
      BIDIRECTIONAL='TRUE';
      INPUT_LOAD='(-0.01,0.01)';
      OUTPUT_LOAD='(1.0,-1.0)';
    'PB16C':
      PIN_NUMBER='(0,0,M8,0,0,0,0)';
      BIDIRECTIONAL='TRUE';
      INPUT_LOAD='(-0.01,0.01)';
      OUTPUT_LOAD='(1.0,-1.0)';
    'PB16D':
      PIN_NUMBER='(0,0,N9,0,0,0,0)';
      BIDIRECTIONAL='TRUE';
      INPUT_LOAD='(-0.01,0.01)';
      OUTPUT_LOAD='(1.0,-1.0)';
    'PB16A||PCLKT2_1':
      PIN_NUMBER='(0,0,T9,0,0,0,0)';
      BIDIRECTIONAL='TRUE';
      INPUT_LOAD='(-0.01,0.01)';
      OUTPUT_LOAD='(1.0,-1.0)';
    'PB16B||PCLKC2_1':
      PIN_NUMBER='(0,0,P9,0,0,0,0)';
      BIDIRECTIONAL='TRUE';
      INPUT_LOAD='(-0.01,0.01)';
      OUTPUT_LOAD='(1.0,-1.0)';
    'PB18A':
      PIN_NUMBER='(0,0,R9,0,0,0,0)';
      BIDIRECTIONAL='TRUE';
      INPUT_LOAD='(-0.01,0.01)';
      OUTPUT_LOAD='(1.0,-1.0)';
    'PB18B':
      PIN_NUMBER='(0,0,T10,0,0,0,0)';
      BIDIRECTIONAL='TRUE';
      INPUT_LOAD='(-0.01,0.01)';
      OUTPUT_LOAD='(1.0,-1.0)';
    'PB18C':
      PIN_NUMBER='(0,0,M9,0,0,0,0)';
      BIDIRECTIONAL='TRUE';
      INPUT_LOAD='(-0.01,0.01)';
      OUTPUT_LOAD='(1.0,-1.0)';
    'PB18D':
      PIN_NUMBER='(0,0,L10,0,0,0,0)';
      BIDIRECTIONAL='TRUE';
      INPUT_LOAD='(-0.01,0.01)';
      OUTPUT_LOAD='(1.0,-1.0)';
    'PB19C':
      PIN_NUMBER='(0,0,N10,0,0,0,0)';
      BIDIRECTIONAL='TRUE';
      INPUT_LOAD='(-0.01,0.01)';
      OUTPUT_LOAD='(1.0,-1.0)';
    'PB19D':
      PIN_NUMBER='(0,0,M11,0,0,0,0)';
      BIDIRECTIONAL='TRUE';
      INPUT_LOAD='(-0.01,0.01)';
      OUTPUT_LOAD='(1.0,-1.0)';
    'PB19A':
      PIN_NUMBER='(0,0,P10,0,0,0,0)';
      BIDIRECTIONAL='TRUE';
      INPUT_LOAD='(-0.01,0.01)';
      OUTPUT_LOAD='(1.0,-1.0)';
    'PB19B':
      PIN_NUMBER='(0,0,R10,0,0,0,0)';
      BIDIRECTIONAL='TRUE';
      INPUT_LOAD='(-0.01,0.01)';
      OUTPUT_LOAD='(1.0,-1.0)';
    'PB21A':
      PIN_NUMBER='(0,0,T11,0,0,0,0)';
      BIDIRECTIONAL='TRUE';
      INPUT_LOAD='(-0.01,0.01)';
      OUTPUT_LOAD='(1.0,-1.0)';
    'PB21B':
      PIN_NUMBER='(0,0,P11,0,0,0,0)';
      BIDIRECTIONAL='TRUE';
      INPUT_LOAD='(-0.01,0.01)';
      OUTPUT_LOAD='(1.0,-1.0)';
    'PB21C':
      PIN_NUMBER='(0,0,M10,0,0,0,0)';
      BIDIRECTIONAL='TRUE';
      INPUT_LOAD='(-0.01,0.01)';
      OUTPUT_LOAD='(1.0,-1.0)';
    'PB21D':
      PIN_NUMBER='(0,0,N11,0,0,0,0)';
      BIDIRECTIONAL='TRUE';
      INPUT_LOAD='(-0.01,0.01)';
      OUTPUT_LOAD='(1.0,-1.0)';
    'PB22C':
      PIN_NUMBER='(0,0,R13,0,0,0,0)';
      BIDIRECTIONAL='TRUE';
      INPUT_LOAD='(-0.01,0.01)';
      OUTPUT_LOAD='(1.0,-1.0)';
    'PB22D':
      PIN_NUMBER='(0,0,T14,0,0,0,0)';
      BIDIRECTIONAL='TRUE';
      INPUT_LOAD='(-0.01,0.01)';
      OUTPUT_LOAD='(1.0,-1.0)';
    'PB22A':
      PIN_NUMBER='(0,0,R11,0,0,0,0)';
      BIDIRECTIONAL='TRUE';
      INPUT_LOAD='(-0.01,0.01)';
      OUTPUT_LOAD='(1.0,-1.0)';
    'PB22B':
      PIN_NUMBER='(0,0,T12,0,0,0,0)';
      BIDIRECTIONAL='TRUE';
      INPUT_LOAD='(-0.01,0.01)';
      OUTPUT_LOAD='(1.0,-1.0)';
    'PB24A':
      PIN_NUMBER='(0,0,P12,0,0,0,0)';
      BIDIRECTIONAL='TRUE';
      INPUT_LOAD='(-0.01,0.01)';
      OUTPUT_LOAD='(1.0,-1.0)';
    'PB24B':
      PIN_NUMBER='(0,0,T13,0,0,0,0)';
      BIDIRECTIONAL='TRUE';
      INPUT_LOAD='(-0.01,0.01)';
      OUTPUT_LOAD='(1.0,-1.0)';
    'PB25A||SN':
      PIN_NUMBER='(0,0,R12,0,0,0,0)';
      BIDIRECTIONAL='TRUE';
      INPUT_LOAD='(-0.01,0.01)';
      OUTPUT_LOAD='(1.0,-1.0)';
    'PB25B||SI||SISPI':
      PIN_NUMBER='(0,0,P13,0,0,0,0)';
      BIDIRECTIONAL='TRUE';
      INPUT_LOAD='(-0.01,0.01)';
      OUTPUT_LOAD='(1.0,-1.0)';
    'PB25C':
      PIN_NUMBER='(0,0,T15,0,0,0,0)';
      BIDIRECTIONAL='TRUE';
      INPUT_LOAD='(-0.01,0.01)';
      OUTPUT_LOAD='(1.0,-1.0)';
    'PB25D':
      PIN_NUMBER='(0,0,R14,0,0,0,0)';
      BIDIRECTIONAL='TRUE';
      INPUT_LOAD='(-0.01,0.01)';
      OUTPUT_LOAD='(1.0,-1.0)';
    'PB3A':
      PIN_NUMBER='(0,0,P4,0,0,0,0)';
      BIDIRECTIONAL='TRUE';
      INPUT_LOAD='(-0.01,0.01)';
      OUTPUT_LOAD='(1.0,-1.0)';
    'PB3B':
      PIN_NUMBER='(0,0,T4,0,0,0,0)';
      BIDIRECTIONAL='TRUE';
      INPUT_LOAD='(-0.01,0.01)';
      OUTPUT_LOAD='(1.0,-1.0)';
    'PB3C':
      PIN_NUMBER='(0,0,T2,0,0,0,0)';
      BIDIRECTIONAL='TRUE';
      INPUT_LOAD='(-0.01,0.01)';
      OUTPUT_LOAD='(1.0,-1.0)';
    'PB3D':
      PIN_NUMBER='(0,0,R3,0,0,0,0)';
      BIDIRECTIONAL='TRUE';
      INPUT_LOAD='(-0.01,0.01)';
      OUTPUT_LOAD='(1.0,-1.0)';
    'PB5A||CSSPIN':
      PIN_NUMBER='(0,0,R5,0,0,0,0)';
      BIDIRECTIONAL='TRUE';
      INPUT_LOAD='(-0.01,0.01)';
      OUTPUT_LOAD='(1.0,-1.0)';
    'PB5B':
      PIN_NUMBER='(0,0,P5,0,0,0,0)';
      BIDIRECTIONAL='TRUE';
      INPUT_LOAD='(-0.01,0.01)';
      OUTPUT_LOAD='(1.0,-1.0)';
    'PB6C':
      PIN_NUMBER='(0,0,T3,0,0,0,0)';
      BIDIRECTIONAL='TRUE';
      INPUT_LOAD='(-0.01,0.01)';
      OUTPUT_LOAD='(1.0,-1.0)';
    'PB6D':
      PIN_NUMBER='(0,0,R4,0,0,0,0)';
      BIDIRECTIONAL='TRUE';
      INPUT_LOAD='(-0.01,0.01)';
      OUTPUT_LOAD='(1.0,-1.0)';
    'PB6A':
      PIN_NUMBER='(0,0,T5,0,0,0,0)';
      BIDIRECTIONAL='TRUE';
      INPUT_LOAD='(-0.01,0.01)';
      OUTPUT_LOAD='(1.0,-1.0)';
    'PB6B':
      PIN_NUMBER='(0,0,R6,0,0,0,0)';
      BIDIRECTIONAL='TRUE';
      INPUT_LOAD='(-0.01,0.01)';
      OUTPUT_LOAD='(1.0,-1.0)';
    'PB8C':
      PIN_NUMBER='(0,0,N6,0,0,0,0)';
      BIDIRECTIONAL='TRUE';
      INPUT_LOAD='(-0.01,0.01)';
      OUTPUT_LOAD='(1.0,-1.0)';
    'PB8D':
      PIN_NUMBER='(0,0,L7,0,0,0,0)';
      BIDIRECTIONAL='TRUE';
      INPUT_LOAD='(-0.01,0.01)';
      OUTPUT_LOAD='(1.0,-1.0)';
    'PB8A||MCLK||CCLK':
      PIN_NUMBER='(0,0,P6,0,0,0,0)';
      BIDIRECTIONAL='TRUE';
      INPUT_LOAD='(-0.01,0.01)';
      OUTPUT_LOAD='(1.0,-1.0)';
    'PB8B||SO||SPISO':
      PIN_NUMBER='(0,0,T6,0,0,0,0)';
      BIDIRECTIONAL='TRUE';
      INPUT_LOAD='(-0.01,0.01)';
      OUTPUT_LOAD='(1.0,-1.0)';
    'PB9A':
      PIN_NUMBER='(0,0,R7,0,0,0,0)';
      BIDIRECTIONAL='TRUE';
      INPUT_LOAD='(-0.01,0.01)';
      OUTPUT_LOAD='(1.0,-1.0)';
    'PB9B':
      PIN_NUMBER='(0,0,P7,0,0,0,0)';
      BIDIRECTIONAL='TRUE';
      INPUT_LOAD='(-0.01,0.01)';
      OUTPUT_LOAD='(1.0,-1.0)';
    'VCCIO2_K8':
      PIN_NUMBER='(0,0,K8,0,0,0,0)';
      PINUSE='POWER';
      NO_LOAD_CHECK='Both';
      NO_IO_CHECK='Both';
      NO_ASSERT_CHECK='TRUE';
      NO_DIR_CHECK='TRUE';
      ALLOW_CONNECT='TRUE';
    'VCCIO2_K9':
      PIN_NUMBER='(0,0,K9,0,0,0,0)';
      PINUSE='POWER';
      NO_LOAD_CHECK='Both';
      NO_IO_CHECK='Both';
      NO_ASSERT_CHECK='TRUE';
      NO_DIR_CHECK='TRUE';
      ALLOW_CONNECT='TRUE';
    'VCCIO2_N12':
      PIN_NUMBER='(0,0,N12,0,0,0,0)';
      PINUSE='POWER';
      NO_LOAD_CHECK='Both';
      NO_IO_CHECK='Both';
      NO_ASSERT_CHECK='TRUE';
      NO_DIR_CHECK='TRUE';
      ALLOW_CONNECT='TRUE';
    'VCCIO2_N5':
      PIN_NUMBER='(0,0,N5,0,0,0,0)';
      PINUSE='POWER';
      NO_LOAD_CHECK='Both';
      NO_IO_CHECK='Both';
      NO_ASSERT_CHECK='TRUE';
      NO_DIR_CHECK='TRUE';
      ALLOW_CONNECT='TRUE';
    'PL11A':
      PIN_NUMBER='(0,0,0,L1,0,0,0)';
      BIDIRECTIONAL='TRUE';
      INPUT_LOAD='(-0.01,0.01)';
      OUTPUT_LOAD='(1.0,-1.0)';
    'PL11B':
      PIN_NUMBER='(0,0,0,L3,0,0,0)';
      BIDIRECTIONAL='TRUE';
      INPUT_LOAD='(-0.01,0.01)';
      OUTPUT_LOAD='(1.0,-1.0)';
    'PL11C':
      PIN_NUMBER='(0,0,0,K4,0,0,0)';
      BIDIRECTIONAL='TRUE';
      INPUT_LOAD='(-0.01,0.01)';
      OUTPUT_LOAD='(1.0,-1.0)';
    'PL11D':
      PIN_NUMBER='(0,0,0,L5,0,0,0)';
      BIDIRECTIONAL='TRUE';
      INPUT_LOAD='(-0.01,0.01)';
      OUTPUT_LOAD='(1.0,-1.0)';
    'PL12C':
      PIN_NUMBER='(0,0,0,K5,0,0,0)';
      BIDIRECTIONAL='TRUE';
      INPUT_LOAD='(-0.01,0.01)';
      OUTPUT_LOAD='(1.0,-1.0)';
    'PL12D':
      PIN_NUMBER='(0,0,0,L4,0,0,0)';
      BIDIRECTIONAL='TRUE';
      INPUT_LOAD='(-0.01,0.01)';
      OUTPUT_LOAD='(1.0,-1.0)';
    'PL12A||PCLKT3_0':
      PIN_NUMBER='(0,0,0,L2,0,0,0)';
      BIDIRECTIONAL='TRUE';
      INPUT_LOAD='(-0.01,0.01)';
      OUTPUT_LOAD='(1.0,-1.0)';
    'PL12B||PCLKC3_0':
      PIN_NUMBER='(0,0,0,M1,0,0,0)';
      BIDIRECTIONAL='TRUE';
      INPUT_LOAD='(-0.01,0.01)';
      OUTPUT_LOAD='(1.0,-1.0)';
    'PL14A':
      PIN_NUMBER='(0,0,0,M2,0,0,0)';
      BIDIRECTIONAL='TRUE';
      INPUT_LOAD='(-0.01,0.01)';
      OUTPUT_LOAD='(1.0,-1.0)';
    'PL14B':
      PIN_NUMBER='(0,0,0,N3,0,0,0)';
      BIDIRECTIONAL='TRUE';
      INPUT_LOAD='(-0.01,0.01)';
      OUTPUT_LOAD='(1.0,-1.0)';
    'PL14C':
      PIN_NUMBER='(0,0,0,R1,0,0,0)';
      BIDIRECTIONAL='TRUE';
      INPUT_LOAD='(-0.01,0.01)';
      OUTPUT_LOAD='(1.0,-1.0)';
    'PL14D':
      PIN_NUMBER='(0,0,0,P2,0,0,0)';
      BIDIRECTIONAL='TRUE';
      INPUT_LOAD='(-0.01,0.01)';
      OUTPUT_LOAD='(1.0,-1.0)';
    'VCCIO3':
      PIN_NUMBER='(0,0,0,M4,0,0,0)';
      PINUSE='POWER';
      NO_LOAD_CHECK='Both';
      NO_IO_CHECK='Both';
      NO_ASSERT_CHECK='TRUE';
      NO_DIR_CHECK='TRUE';
      ALLOW_CONNECT='TRUE';
    'PL13C':
      PIN_NUMBER='(0,0,0,N2,0,0,0)';
      BIDIRECTIONAL='TRUE';
      INPUT_LOAD='(-0.01,0.01)';
      OUTPUT_LOAD='(1.0,-1.0)';
    'PL13D':
      PIN_NUMBER='(0,0,0,P1,0,0,0)';
      BIDIRECTIONAL='TRUE';
      INPUT_LOAD='(-0.01,0.01)';
      OUTPUT_LOAD='(1.0,-1.0)';
    'PL13A':
      PIN_NUMBER='(0,0,0,M3,0,0,0)';
      BIDIRECTIONAL='TRUE';
      INPUT_LOAD='(-0.01,0.01)';
      OUTPUT_LOAD='(1.0,-1.0)';
    'PL13B':
      PIN_NUMBER='(0,0,0,N1,0,0,0)';
      BIDIRECTIONAL='TRUE';
      INPUT_LOAD='(-0.01,0.01)';
      OUTPUT_LOAD='(1.0,-1.0)';
    'PL6A':
      PIN_NUMBER='(0,0,0,0,G1,0,0)';
      BIDIRECTIONAL='TRUE';
      INPUT_LOAD='(-0.01,0.01)';
      OUTPUT_LOAD='(1.0,-1.0)';
    'PL6B':
      PIN_NUMBER='(0,0,0,0,H2,0,0)';
      BIDIRECTIONAL='TRUE';
      INPUT_LOAD='(-0.01,0.01)';
      OUTPUT_LOAD='(1.0,-1.0)';
    'PL6C':
      PIN_NUMBER='(0,0,0,0,H4,0,0)';
      BIDIRECTIONAL='TRUE';
      INPUT_LOAD='(-0.01,0.01)';
      OUTPUT_LOAD='(1.0,-1.0)';
    'PL6D':
      PIN_NUMBER='(0,0,0,0,J6,0,0)';
      BIDIRECTIONAL='TRUE';
      INPUT_LOAD='(-0.01,0.01)';
      OUTPUT_LOAD='(1.0,-1.0)';
    'PL7A':
      PIN_NUMBER='(0,0,0,0,H3,0,0)';
      BIDIRECTIONAL='TRUE';
      INPUT_LOAD='(-0.01,0.01)';
      OUTPUT_LOAD='(1.0,-1.0)';
    'PL7B':
      PIN_NUMBER='(0,0,0,0,H1,0,0)';
      BIDIRECTIONAL='TRUE';
      INPUT_LOAD='(-0.01,0.01)';
      OUTPUT_LOAD='(1.0,-1.0)';
    'PL7C||PCLKT4_0':
      PIN_NUMBER='(0,0,0,0,J1,0,0)';
      BIDIRECTIONAL='TRUE';
      INPUT_LOAD='(-0.01,0.01)';
      OUTPUT_LOAD='(1.0,-1.0)';
    'PL7D||PCLKC4_0':
      PIN_NUMBER='(0,0,0,0,J3,0,0)';
      BIDIRECTIONAL='TRUE';
      INPUT_LOAD='(-0.01,0.01)';
      OUTPUT_LOAD='(1.0,-1.0)';
    'PL10C':
      PIN_NUMBER='(0,0,0,0,J5,0,0)';
      BIDIRECTIONAL='TRUE';
      INPUT_LOAD='(-0.01,0.01)';
      OUTPUT_LOAD='(1.0,-1.0)';
    'PL10D':
      PIN_NUMBER='(0,0,0,0,K6,0,0)';
      BIDIRECTIONAL='TRUE';
      INPUT_LOAD='(-0.01,0.01)';
      OUTPUT_LOAD='(1.0,-1.0)';
    'PL10A':
      PIN_NUMBER='(0,0,0,0,K3,0,0)';
      BIDIRECTIONAL='TRUE';
      INPUT_LOAD='(-0.01,0.01)';
      OUTPUT_LOAD='(1.0,-1.0)';
    'PL10B':
      PIN_NUMBER='(0,0,0,0,K2,0,0)';
      BIDIRECTIONAL='TRUE';
      INPUT_LOAD='(-0.01,0.01)';
      OUTPUT_LOAD='(1.0,-1.0)';
    'PL9A':
      PIN_NUMBER='(0,0,0,0,J2,0,0)';
      BIDIRECTIONAL='TRUE';
      INPUT_LOAD='(-0.01,0.01)';
      OUTPUT_LOAD='(1.0,-1.0)';
    'PL9B':
      PIN_NUMBER='(0,0,0,0,K1,0,0)';
      BIDIRECTIONAL='TRUE';
      INPUT_LOAD='(-0.01,0.01)';
      OUTPUT_LOAD='(1.0,-1.0)';
    'PL9C':
      PIN_NUMBER='(0,0,0,0,H5,0,0)';
      BIDIRECTIONAL='TRUE';
      INPUT_LOAD='(-0.01,0.01)';
      OUTPUT_LOAD='(1.0,-1.0)';
    'PL9D':
      PIN_NUMBER='(0,0,0,0,J4,0,0)';
      BIDIRECTIONAL='TRUE';
      INPUT_LOAD='(-0.01,0.01)';
      OUTPUT_LOAD='(1.0,-1.0)';
    'VCCIO4_H7':
      PIN_NUMBER='(0,0,0,0,H7,0,0)';
      PINUSE='POWER';
      NO_LOAD_CHECK='Both';
      NO_IO_CHECK='Both';
      NO_ASSERT_CHECK='TRUE';
      NO_DIR_CHECK='TRUE';
      ALLOW_CONNECT='TRUE';
    'VCCIO4_J7':
      PIN_NUMBER='(0,0,0,0,J7,0,0)';
      PINUSE='POWER';
      NO_LOAD_CHECK='Both';
      NO_IO_CHECK='Both';
      NO_ASSERT_CHECK='TRUE';
      NO_DIR_CHECK='TRUE';
      ALLOW_CONNECT='TRUE';
    'PL1C':
      PIN_NUMBER='(0,0,0,0,0,B1,0)';
      BIDIRECTIONAL='TRUE';
      INPUT_LOAD='(-0.01,0.01)';
      OUTPUT_LOAD='(1.0,-1.0)';
    'PL1D':
      PIN_NUMBER='(0,0,0,0,0,C2,0)';
      BIDIRECTIONAL='TRUE';
      INPUT_LOAD='(-0.01,0.01)';
      OUTPUT_LOAD='(1.0,-1.0)';
    'PL1A||L_GPLLT_FB':
      PIN_NUMBER='(0,0,0,0,0,D3,0)';
      BIDIRECTIONAL='TRUE';
      INPUT_LOAD='(-0.01,0.01)';
      OUTPUT_LOAD='(1.0,-1.0)';
    'PL1B||L_GPLLC_FB':
      PIN_NUMBER='(0,0,0,0,0,D1,0)';
      BIDIRECTIONAL='TRUE';
      INPUT_LOAD='(-0.01,0.01)';
      OUTPUT_LOAD='(1.0,-1.0)';
    'PL2A||L_GPLLT_IN':
      PIN_NUMBER='(0,0,0,0,0,E2,0)';
      BIDIRECTIONAL='TRUE';
      INPUT_LOAD='(-0.01,0.01)';
      OUTPUT_LOAD='(1.0,-1.0)';
    'PL2B||L_GPLLC_IN':
      PIN_NUMBER='(0,0,0,0,0,E3,0)';
      BIDIRECTIONAL='TRUE';
      INPUT_LOAD='(-0.01,0.01)';
      OUTPUT_LOAD='(1.0,-1.0)';
    'PL2C':
      PIN_NUMBER='(0,0,0,0,0,C1,0)';
      BIDIRECTIONAL='TRUE';
      INPUT_LOAD='(-0.01,0.01)';
      OUTPUT_LOAD='(1.0,-1.0)';
    'PL2D':
      PIN_NUMBER='(0,0,0,0,0,D2,0)';
      BIDIRECTIONAL='TRUE';
      INPUT_LOAD='(-0.01,0.01)';
      OUTPUT_LOAD='(1.0,-1.0)';
    'PL3A||PCLKT5_0':
      PIN_NUMBER='(0,0,0,0,0,E1,0)';
      BIDIRECTIONAL='TRUE';
      INPUT_LOAD='(-0.01,0.01)';
      OUTPUT_LOAD='(1.0,-1.0)';
    'PL3B||PCLKC5_0':
      PIN_NUMBER='(0,0,0,0,0,F2,0)';
      BIDIRECTIONAL='TRUE';
      INPUT_LOAD='(-0.01,0.01)';
      OUTPUT_LOAD='(1.0,-1.0)';
    'PL3C':
      PIN_NUMBER='(0,0,0,0,0,F4,0)';
      BIDIRECTIONAL='TRUE';
      INPUT_LOAD='(-0.01,0.01)';
      OUTPUT_LOAD='(1.0,-1.0)';
    'PL3D':
      PIN_NUMBER='(0,0,0,0,0,G6,0)';
      BIDIRECTIONAL='TRUE';
      INPUT_LOAD='(-0.01,0.01)';
      OUTPUT_LOAD='(1.0,-1.0)';
    'PL5A':
      PIN_NUMBER='(0,0,0,0,0,G2,0)';
      BIDIRECTIONAL='TRUE';
      INPUT_LOAD='(-0.01,0.01)';
      OUTPUT_LOAD='(1.0,-1.0)';
    'PL5B':
      PIN_NUMBER='(0,0,0,0,0,G3,0)';
      BIDIRECTIONAL='TRUE';
      INPUT_LOAD='(-0.01,0.01)';
      OUTPUT_LOAD='(1.0,-1.0)';
    'PL5C':
      PIN_NUMBER='(0,0,0,0,0,F5,0)';
      BIDIRECTIONAL='TRUE';
      INPUT_LOAD='(-0.01,0.01)';
      OUTPUT_LOAD='(1.0,-1.0)';
    'PL5D':
      PIN_NUMBER='(0,0,0,0,0,H6,0)';
      BIDIRECTIONAL='TRUE';
      INPUT_LOAD='(-0.01,0.01)';
      OUTPUT_LOAD='(1.0,-1.0)';
    'VCCIO5':
      PIN_NUMBER='(0,0,0,0,0,E4,0)';
      PINUSE='POWER';
      NO_LOAD_CHECK='Both';
      NO_IO_CHECK='Both';
      NO_ASSERT_CHECK='TRUE';
      NO_DIR_CHECK='TRUE';
      ALLOW_CONNECT='TRUE';
    'PL4C':
      PIN_NUMBER='(0,0,0,0,0,G5,0)';
      BIDIRECTIONAL='TRUE';
      INPUT_LOAD='(-0.01,0.01)';
      OUTPUT_LOAD='(1.0,-1.0)';
    'PL4D':
      PIN_NUMBER='(0,0,0,0,0,G4,0)';
      BIDIRECTIONAL='TRUE';
      INPUT_LOAD='(-0.01,0.01)';
      OUTPUT_LOAD='(1.0,-1.0)';
    'PL4A':
      PIN_NUMBER='(0,0,0,0,0,F3,0)';
      BIDIRECTIONAL='TRUE';
      INPUT_LOAD='(-0.01,0.01)';
      OUTPUT_LOAD='(1.0,-1.0)';
    'PL4B':
      PIN_NUMBER='(0,0,0,0,0,F1,0)';
      BIDIRECTIONAL='TRUE';
      INPUT_LOAD='(-0.01,0.01)';
      OUTPUT_LOAD='(1.0,-1.0)';
    'GND_B2':
      PIN_NUMBER='(0,0,0,0,0,0,B2)';
      PINUSE='POWER';
      NO_LOAD_CHECK='Both';
      NO_IO_CHECK='Both';
      NO_ASSERT_CHECK='TRUE';
      NO_DIR_CHECK='TRUE';
      ALLOW_CONNECT='TRUE';
    'GND_B15':
      PIN_NUMBER='(0,0,0,0,0,0,B15)';
      PINUSE='POWER';
      NO_LOAD_CHECK='Both';
      NO_IO_CHECK='Both';
      NO_ASSERT_CHECK='TRUE';
      NO_DIR_CHECK='TRUE';
      ALLOW_CONNECT='TRUE';
    'GND_C3':
      PIN_NUMBER='(0,0,0,0,0,0,C3)';
      PINUSE='POWER';
      NO_LOAD_CHECK='Both';
      NO_IO_CHECK='Both';
      NO_ASSERT_CHECK='TRUE';
      NO_DIR_CHECK='TRUE';
      ALLOW_CONNECT='TRUE';
    'GND_C14':
      PIN_NUMBER='(0,0,0,0,0,0,C14)';
      PINUSE='POWER';
      NO_LOAD_CHECK='Both';
      NO_IO_CHECK='Both';
      NO_ASSERT_CHECK='TRUE';
      NO_DIR_CHECK='TRUE';
      ALLOW_CONNECT='TRUE';
    'GND_D4':
      PIN_NUMBER='(0,0,0,0,0,0,D4)';
      PINUSE='POWER';
      NO_LOAD_CHECK='Both';
      NO_IO_CHECK='Both';
      NO_ASSERT_CHECK='TRUE';
      NO_DIR_CHECK='TRUE';
      ALLOW_CONNECT='TRUE';
    'GND_D13':
      PIN_NUMBER='(0,0,0,0,0,0,D13)';
      PINUSE='POWER';
      NO_LOAD_CHECK='Both';
      NO_IO_CHECK='Both';
      NO_ASSERT_CHECK='TRUE';
      NO_DIR_CHECK='TRUE';
      ALLOW_CONNECT='TRUE';
    'GND_E5':
      PIN_NUMBER='(0,0,0,0,0,0,E5)';
      PINUSE='POWER';
      NO_LOAD_CHECK='Both';
      NO_IO_CHECK='Both';
      NO_ASSERT_CHECK='TRUE';
      NO_DIR_CHECK='TRUE';
      ALLOW_CONNECT='TRUE';
    'GND_E12':
      PIN_NUMBER='(0,0,0,0,0,0,E12)';
      PINUSE='POWER';
      NO_LOAD_CHECK='Both';
      NO_IO_CHECK='Both';
      NO_ASSERT_CHECK='TRUE';
      NO_DIR_CHECK='TRUE';
      ALLOW_CONNECT='TRUE';
    'GND_F6':
      PIN_NUMBER='(0,0,0,0,0,0,F6)';
      PINUSE='POWER';
      NO_LOAD_CHECK='Both';
      NO_IO_CHECK='Both';
      NO_ASSERT_CHECK='TRUE';
      NO_DIR_CHECK='TRUE';
      ALLOW_CONNECT='TRUE';
    'GND_F11':
      PIN_NUMBER='(0,0,0,0,0,0,F11)';
      PINUSE='POWER';
      NO_LOAD_CHECK='Both';
      NO_IO_CHECK='Both';
      NO_ASSERT_CHECK='TRUE';
      NO_DIR_CHECK='TRUE';
      ALLOW_CONNECT='TRUE';
    'GND_H8':
      PIN_NUMBER='(0,0,0,0,0,0,H8)';
      PINUSE='POWER';
      NO_LOAD_CHECK='Both';
      NO_IO_CHECK='Both';
      NO_ASSERT_CHECK='TRUE';
      NO_DIR_CHECK='TRUE';
      ALLOW_CONNECT='TRUE';
    'GND_H9':
      PIN_NUMBER='(0,0,0,0,0,0,H9)';
      PINUSE='POWER';
      NO_LOAD_CHECK='Both';
      NO_IO_CHECK='Both';
      NO_ASSERT_CHECK='TRUE';
      NO_DIR_CHECK='TRUE';
      ALLOW_CONNECT='TRUE';
    'GND_J8':
      PIN_NUMBER='(0,0,0,0,0,0,J8)';
      PINUSE='POWER';
      NO_LOAD_CHECK='Both';
      NO_IO_CHECK='Both';
      NO_ASSERT_CHECK='TRUE';
      NO_DIR_CHECK='TRUE';
      ALLOW_CONNECT='TRUE';
    'GND_J9':
      PIN_NUMBER='(0,0,0,0,0,0,J9)';
      PINUSE='POWER';
      NO_LOAD_CHECK='Both';
      NO_IO_CHECK='Both';
      NO_ASSERT_CHECK='TRUE';
      NO_DIR_CHECK='TRUE';
      ALLOW_CONNECT='TRUE';
    'GND_L6':
      PIN_NUMBER='(0,0,0,0,0,0,L6)';
      PINUSE='POWER';
      NO_LOAD_CHECK='Both';
      NO_IO_CHECK='Both';
      NO_ASSERT_CHECK='TRUE';
      NO_DIR_CHECK='TRUE';
      ALLOW_CONNECT='TRUE';
    'GND_L11':
      PIN_NUMBER='(0,0,0,0,0,0,L11)';
      PINUSE='POWER';
      NO_LOAD_CHECK='Both';
      NO_IO_CHECK='Both';
      NO_ASSERT_CHECK='TRUE';
      NO_DIR_CHECK='TRUE';
      ALLOW_CONNECT='TRUE';
    'GND_M5':
      PIN_NUMBER='(0,0,0,0,0,0,M5)';
      PINUSE='POWER';
      NO_LOAD_CHECK='Both';
      NO_IO_CHECK='Both';
      NO_ASSERT_CHECK='TRUE';
      NO_DIR_CHECK='TRUE';
      ALLOW_CONNECT='TRUE';
    'GND_M12':
      PIN_NUMBER='(0,0,0,0,0,0,M12)';
      PINUSE='POWER';
      NO_LOAD_CHECK='Both';
      NO_IO_CHECK='Both';
      NO_ASSERT_CHECK='TRUE';
      NO_DIR_CHECK='TRUE';
      ALLOW_CONNECT='TRUE';
    'GND_N4':
      PIN_NUMBER='(0,0,0,0,0,0,N4)';
      PINUSE='POWER';
      NO_LOAD_CHECK='Both';
      NO_IO_CHECK='Both';
      NO_ASSERT_CHECK='TRUE';
      NO_DIR_CHECK='TRUE';
      ALLOW_CONNECT='TRUE';
    'GND_N13':
      PIN_NUMBER='(0,0,0,0,0,0,N13)';
      PINUSE='POWER';
      NO_LOAD_CHECK='Both';
      NO_IO_CHECK='Both';
      NO_ASSERT_CHECK='TRUE';
      NO_DIR_CHECK='TRUE';
      ALLOW_CONNECT='TRUE';
    'GND_P3':
      PIN_NUMBER='(0,0,0,0,0,0,P3)';
      PINUSE='POWER';
      NO_LOAD_CHECK='Both';
      NO_IO_CHECK='Both';
      NO_ASSERT_CHECK='TRUE';
      NO_DIR_CHECK='TRUE';
      ALLOW_CONNECT='TRUE';
    'GND_P14':
      PIN_NUMBER='(0,0,0,0,0,0,P14)';
      PINUSE='POWER';
      NO_LOAD_CHECK='Both';
      NO_IO_CHECK='Both';
      NO_ASSERT_CHECK='TRUE';
      NO_DIR_CHECK='TRUE';
      ALLOW_CONNECT='TRUE';
    'GND_R2':
      PIN_NUMBER='(0,0,0,0,0,0,R2)';
      PINUSE='POWER';
      NO_LOAD_CHECK='Both';
      NO_IO_CHECK='Both';
      NO_ASSERT_CHECK='TRUE';
      NO_DIR_CHECK='TRUE';
      ALLOW_CONNECT='TRUE';
    'GND_R15':
      PIN_NUMBER='(0,0,0,0,0,0,R15)';
      PINUSE='POWER';
      NO_LOAD_CHECK='Both';
      NO_IO_CHECK='Both';
      NO_ASSERT_CHECK='TRUE';
      NO_DIR_CHECK='TRUE';
      ALLOW_CONNECT='TRUE';
    'NC1':
      PIN_NUMBER='(0,0,0,0,0,0,A2)';
      OUTPUT_TYPE='(TS,TS)';
      INPUT_LOAD='(-0.01,0.01)';
      OUTPUT_LOAD='(1.0,-1.0)';
    'VCC_T16':
      PIN_NUMBER='(0,0,0,0,0,0,T16)';
      PINUSE='POWER';
      NO_LOAD_CHECK='Both';
      NO_IO_CHECK='Both';
      NO_ASSERT_CHECK='TRUE';
      NO_DIR_CHECK='TRUE';
      ALLOW_CONNECT='TRUE';
    'VCC_T1':
      PIN_NUMBER='(0,0,0,0,0,0,T1)';
      PINUSE='POWER';
      NO_LOAD_CHECK='Both';
      NO_IO_CHECK='Both';
      NO_ASSERT_CHECK='TRUE';
      NO_DIR_CHECK='TRUE';
      ALLOW_CONNECT='TRUE';
    'VCC_K10':
      PIN_NUMBER='(0,0,0,0,0,0,K10)';
      PINUSE='POWER';
      NO_LOAD_CHECK='Both';
      NO_IO_CHECK='Both';
      NO_ASSERT_CHECK='TRUE';
      NO_DIR_CHECK='TRUE';
      ALLOW_CONNECT='TRUE';
    'VCC_K7':
      PIN_NUMBER='(0,0,0,0,0,0,K7)';
      PINUSE='POWER';
      NO_LOAD_CHECK='Both';
      NO_IO_CHECK='Both';
      NO_ASSERT_CHECK='TRUE';
      NO_DIR_CHECK='TRUE';
      ALLOW_CONNECT='TRUE';
    'VCC_G10':
      PIN_NUMBER='(0,0,0,0,0,0,G10)';
      PINUSE='POWER';
      NO_LOAD_CHECK='Both';
      NO_IO_CHECK='Both';
      NO_ASSERT_CHECK='TRUE';
      NO_DIR_CHECK='TRUE';
      ALLOW_CONNECT='TRUE';
    'VCC_G7':
      PIN_NUMBER='(0,0,0,0,0,0,G7)';
      PINUSE='POWER';
      NO_LOAD_CHECK='Both';
      NO_IO_CHECK='Both';
      NO_ASSERT_CHECK='TRUE';
      NO_DIR_CHECK='TRUE';
      ALLOW_CONNECT='TRUE';
    'VCC_A16':
      PIN_NUMBER='(0,0,0,0,0,0,A16)';
      PINUSE='POWER';
      NO_LOAD_CHECK='Both';
      NO_IO_CHECK='Both';
      NO_ASSERT_CHECK='TRUE';
      NO_DIR_CHECK='TRUE';
      ALLOW_CONNECT='TRUE';
    'VCC_A1':
      PIN_NUMBER='(0,0,0,0,0,0,A1)';
      PINUSE='POWER';
      NO_LOAD_CHECK='Both';
      NO_IO_CHECK='Both';
      NO_ASSERT_CHECK='TRUE';
      NO_DIR_CHECK='TRUE';
      ALLOW_CONNECT='TRUE';
  end_pin;
  body
    PART_NAME='LCMXO3LF2100C5BG256C';
    BODY_NAME='LCMXO3LF2100C5BG256C';
    PHYS_DES_PREFIX='U';
    CLASS='IC';
  end_body;
end_primitive;

END.
